# T6G (Grand Teton) — schematic netlist excerpt (pin names and nets, part order shuffled) for the footprints in the layout excerpt that follows; sources: Cadence DE-HDL packaged netlist, KiCad conversion of 04192023_DAF0TMB3IC0_F0TG_MB_C_brd_V02_OCP.brd

R8075  Q_RES  1K 1% CHIP  pkg 0402LF  page 200 : A = PVDD18_S5_P0 ; B = PVDDCR_CPU1_P0_OCP_N_R
PL55  Q_INDUCTOR  90NH/155A IND  pkg SMLF  page 225 : \1\ = SW_PVDD11_S3_P1_SW2 ; \2\ = PVDD11_S3_P1

(kicad_pcb
	(version 20260206)
	(generator "pcbnew")
	(generator_version "10.0")
	(general
		(thickness 1.6)
		(legacy_teardrops no)
	)
	(paper "A4")
	(title_block
		(title "04192023_DAF0TMB3IC0_F0TG_MB_C_brd_V02_OCP.brd")
		(comment 1 "Grand Teton / footprints 2526-2527 of 8354")
	)
	(layers
		(0 "F.Cu" signal "TOP")
		(4 "In1.Cu" signal "GND")
		(6 "In2.Cu" signal "IN1")
		(8 "In3.Cu" signal "GND1")
		(10 "In4.Cu" signal "IN2")
		(12 "In5.Cu" signal "GND2")
		(14 "In6.Cu" signal "IN3")
		(16 "In7.Cu" signal "GND3")
		(18 "In8.Cu" signal "VCC")
		(20 "In9.Cu" signal "VCC1")
		(22 "In10.Cu" signal "GND4")
		(24 "In11.Cu" signal "IN4")
		(26 "In12.Cu" signal "GND5")
		(28 "In13.Cu" signal "IN5")
		(30 "In14.Cu" signal "GND6")
		(32 "In15.Cu" signal "IN6")
		(34 "In16.Cu" signal "GND7")
		(2 "B.Cu" signal "BOTTOM")
		(9 "F.Adhes" user "F.Adhesive")
		(11 "B.Adhes" user "B.Adhesive")
		(13 "F.Paste" user "Package Geometry/Pastemask Top")
		(15 "B.Paste" user "Package Geometry/Pastemask Bottom")
		(5 "F.SilkS" user "Ref Des/Silkscreen Top")
		(7 "B.SilkS" user "Ref Des/Silkscreen Bottom")
		(1 "F.Mask" user "Board Geometry/Soldermask Top")
		(3 "B.Mask" user "Board Geometry/Soldermask Bottom")
		(17 "Dwgs.User" user "User.Drawings")
		(19 "Cmts.User" user "User.Comments")
		(21 "Eco1.User" user "User.Eco1")
		(23 "Eco2.User" user "User.Eco2")
		(25 "Edge.Cuts" user "Board Geometry/Outline")
		(27 "Margin" user)
		(31 "F.CrtYd" user "Package Geometry/Place Bound Top")
		(29 "B.CrtYd" user "Package Geometry/Place Bound Bottom")
		(35 "F.Fab" user "Ref Des/Assembly Top")
		(33 "B.Fab" user "Ref Des/Assembly Bottom")
	)
	(footprint ""
		(layer "F.Cu")
		(at 191.246506 -342.487758 -90)
		(property "Reference" "PL55"
			(at -15.522956 3.048254 0)
			(unlocked yes)
			(layer "F.SilkS")
			(effects
				(font
					(size 0.7874 0.5842)
					(thickness 0.1524)
				)
				(justify left)
			)
		)
		(property "Value" ""
			(at 0 0 270)
			(layer "F.Fab")
			(effects
				(font
					(size 1.27 1.27)
				)
			)
		)
		(duplicate_pad_numbers_are_jumpers no)
		(fp_line
			(start -4.99999 3.849878)
			(end -4.99999 2.23901)
			(stroke
				(width 0.1524)
				(type default)
			)
			(layer "F.SilkS")
		)
		(fp_line
			(start 4.99999 3.849878)
			(end -4.99999 3.849878)
			(stroke
				(width 0.1524)
				(type default)
			)
			(layer "F.SilkS")
		)
		(fp_line
			(start 4.99999 2.23901)
			(end 4.99999 3.849878)
			(stroke
				(width 0.1524)
				(type default)
			)
			(layer "F.SilkS")
		)
		(fp_line
			(start -4.99999 -2.23901)
			(end -4.99999 -3.849878)
			(stroke
				(width 0.1524)
				(type default)
			)
			(layer "F.SilkS")
		)
		(fp_line
			(start -4.99999 -3.849878)
			(end 4.99999 -3.849878)
			(stroke
				(width 0.1524)
				(type default)
			)
			(layer "F.SilkS")
		)
		(fp_line
			(start 4.99999 -3.849878)
			(end 4.99999 -2.23901)
			(stroke
				(width 0.1524)
				(type default)
			)
			(layer "F.SilkS")
		)
		(fp_line
			(start -4.99999 3.849878)
			(end -4.99999 -3.849878)
			(stroke
				(width 0.1)
				(type default)
			)
			(layer "F.Fab")
		)
		(fp_line
			(start 4.99999 3.849878)
			(end -4.99999 3.849878)
			(stroke
				(width 0.1)
				(type default)
			)
			(layer "F.Fab")
		)
		(fp_line
			(start -4.99999 -3.849878)
			(end 4.99999 -3.849878)
			(stroke
				(width 0.1)
				(type default)
			)
			(layer "F.Fab")
		)
		(fp_line
			(start 4.99999 -3.849878)
			(end 4.99999 3.849878)
			(stroke
				(width 0.1)
				(type default)
			)
			(layer "F.Fab")
		)
		(pad "1" smd rect
			(at -3.299968 0 270)
			(size 3.302 4.2164)
			(layers "F.Cu" "F.Mask" "F.Paste")
			(net "SW_PVDD11_S3_P1_SW2")
		)
		(pad "2" smd rect
			(at 3.299968 0 270)
			(size 3.302 4.2164)
			(layers "F.Cu" "F.Mask" "F.Paste")
			(net "PVDD11_S3_P1")
		)
	)
	(footprint ""
		(layer "F.Cu")
		(at 316.738 -359.283 180)
		(property "Reference" "R8075"
			(at 0 0 180)
			(layer "F.SilkS")
			(hide yes)
			(effects
				(font
					(size 1.27 1.27)
				)
			)
		)
		(property "Value" ""
			(at 0 0 180)
			(layer "F.Fab")
			(effects
				(font
					(size 1.27 1.27)
				)
			)
		)
		(duplicate_pad_numbers_are_jumpers no)
		(fp_line
			(start 0.7874 0.4064)
			(end -0.7874 0.4064)
			(stroke
				(width 0.1524)
				(type default)
			)
			(layer "F.SilkS")
		)
		(fp_line
			(start 0.7874 -0.4064)
			(end 0.7874 0.4064)
			(stroke
				(width 0.1524)
				(type default)
			)
			(layer "F.SilkS")
		)
		(fp_line
			(start -0.7874 0.4064)
			(end -0.7874 -0.4064)
			(stroke
				(width 0.1524)
				(type default)
			)
			(layer "F.SilkS")
		)
		(fp_line
			(start -0.7874 -0.4064)
			(end 0.7874 -0.4064)
			(stroke
				(width 0.1524)
				(type default)
			)
			(layer "F.SilkS")
		)
		(fp_line
			(start 0.67945 0.3048)
			(end 0.120396 0.3048)
			(stroke
				(width 0.1)
				(type default)
			)
			(layer "F.Fab")
		)
		(fp_line
			(start 0.67945 -0.3048)
			(end 0.67945 0.3048)
			(stroke
				(width 0.1)
				(type default)
			)
			(layer "F.Fab")
		)
		(fp_line
			(start 0.12065 -0.2794)
			(end 0.12065 -0.3048)
			(stroke
				(width 0.1)
				(type default)
			)
			(layer "F.Fab")
		)
		(fp_line
			(start 0.12065 -0.3048)
			(end 0.67945 -0.3048)
			(stroke
				(width 0.1)
				(type default)
			)
			(layer "F.Fab")
		)
		(fp_line
			(start 0.120396 0.3048)
			(end 0.120396 0.2794)
			(stroke
				(width 0.1)
				(type default)
			)
			(layer "F.Fab")
		)
		(fp_line
			(start 0.120396 0.2794)
			(end -0.12065 0.2794)
			(stroke
				(width 0.1)
				(type default)
			)
			(layer "F.Fab")
		)
		(fp_line
			(start -0.12065 0.3048)
			(end -0.67945 0.3048)
			(stroke
				(width 0.1)
				(type default)
			)
			(layer "F.Fab")
		)
		(fp_line
			(start -0.12065 0.2794)
			(end -0.12065 0.3048)
			(stroke
				(width 0.1)
				(type default)
			)
			(layer "F.Fab")
		)
		(fp_line
			(start -0.12065 -0.2794)
			(end 0.12065 -0.2794)
			(stroke
				(width 0.1)
				(type default)
			)
			(layer "F.Fab")
		)
		(fp_line
			(start -0.12065 -0.305054)
			(end -0.12065 -0.2794)
			(stroke
				(width 0.1)
				(type default)
			)
			(layer "F.Fab")
		)
		(fp_line
			(start -0.67945 0.3048)
			(end -0.67945 -0.305054)
			(stroke
				(width 0.1)
				(type default)
			)
			(layer "F.Fab")
		)
		(fp_line
			(start -0.67945 -0.305054)
			(end -0.12065 -0.305054)
			(stroke
				(width 0.1)
				(type default)
			)
			(layer "F.Fab")
		)
		(pad "1" smd circle
			(at -0.40005 0 180)
			(size 0 0)
			(layers "F.Cu" "F.Mask" "F.Paste")
			(net "PVDD18_S5_P0")
		)
		(pad "2" smd circle
			(at 0.40005 0 180)
			(size 0 0)
			(layers "F.Cu" "F.Mask" "F.Paste")
			(net "PVDDCR_CPU1_P0_OCP_N_R")
		)
	)
)
